# T6G (Grand Teton) — schematic netlist excerpt (pin names and nets, part order shuffled) for the footprints in the layout excerpt that follows; sources: Cadence DE-HDL packaged netlist, KiCad conversion of 04192023_DAF0TMB3IC0_F0TG_MB_C_brd_V02_OCP.brd

PD101  DIODE_TVS  SMF14A IC  pkg SOD123F  page 134 : A = GND ; C = P12V_AUX
R6114  Q_RES  2K 1% CHIP  pkg 0402LF  page 83 : A = RST_PERST_CPU0_SWB_N ; B = GND
C1534  Q_CAP_DIFFBUS  DIFF BUS_0.22UF 6.3V 20% X6S  pkg C0201  page 67 : \1\ = P5E_CPU1_P3_TX_C_DN<6> ; \2\ = P5E_CPU1_P3_TX_DN<6>

(kicad_pcb
	(version 20260206)
	(generator "pcbnew")
	(generator_version "10.0")
	(general
		(thickness 1.6)
		(legacy_teardrops no)
	)
	(paper "A4")
	(title_block
		(title "04192023_DAF0TMB3IC0_F0TG_MB_C_brd_V02_OCP.brd")
		(comment 1 "Grand Teton / footprints 324-326 of 8354")
	)
	(layers
		(0 "F.Cu" signal "TOP")
		(4 "In1.Cu" signal "GND")
		(6 "In2.Cu" signal "IN1")
		(8 "In3.Cu" signal "GND1")
		(10 "In4.Cu" signal "IN2")
		(12 "In5.Cu" signal "GND2")
		(14 "In6.Cu" signal "IN3")
		(16 "In7.Cu" signal "GND3")
		(18 "In8.Cu" signal "VCC")
		(20 "In9.Cu" signal "VCC1")
		(22 "In10.Cu" signal "GND4")
		(24 "In11.Cu" signal "IN4")
		(26 "In12.Cu" signal "GND5")
		(28 "In13.Cu" signal "IN5")
		(30 "In14.Cu" signal "GND6")
		(32 "In15.Cu" signal "IN6")
		(34 "In16.Cu" signal "GND7")
		(2 "B.Cu" signal "BOTTOM")
		(9 "F.Adhes" user "F.Adhesive")
		(11 "B.Adhes" user "B.Adhesive")
		(13 "F.Paste" user "Package Geometry/Pastemask Top")
		(15 "B.Paste" user "Package Geometry/Pastemask Bottom")
		(5 "F.SilkS" user "Ref Des/Silkscreen Top")
		(7 "B.SilkS" user "Ref Des/Silkscreen Bottom")
		(1 "F.Mask" user "Board Geometry/Soldermask Top")
		(3 "B.Mask" user "Board Geometry/Soldermask Bottom")
		(17 "Dwgs.User" user "User.Drawings")
		(19 "Cmts.User" user "User.Comments")
		(21 "Eco1.User" user "User.Eco1")
		(23 "Eco2.User" user "User.Eco2")
		(25 "Edge.Cuts" user "Board Geometry/Outline")
		(27 "Margin" user)
		(31 "F.CrtYd" user "Package Geometry/Place Bound Top")
		(29 "B.CrtYd" user "Package Geometry/Place Bound Bottom")
		(35 "F.Fab" user "Ref Des/Assembly Top")
		(33 "B.Fab" user "Ref Des/Assembly Bottom")
	)
	(footprint ""
		(layer "F.Cu")
		(at 205.214982 -115.657376 180)
		(property "Reference" "R6114"
			(at 0 0 180)
			(layer "F.SilkS")
			(hide yes)
			(effects
				(font
					(size 1.27 1.27)
				)
			)
		)
		(property "Value" ""
			(at 0 0 180)
			(layer "F.Fab")
			(effects
				(font
					(size 1.27 1.27)
				)
			)
		)
		(duplicate_pad_numbers_are_jumpers no)
		(fp_line
			(start 0.7874 0.4064)
			(end -0.7874 0.4064)
			(stroke
				(width 0.1524)
				(type default)
			)
			(layer "F.SilkS")
		)
		(fp_line
			(start 0.7874 -0.4064)
			(end 0.7874 0.4064)
			(stroke
				(width 0.1524)
				(type default)
			)
			(layer "F.SilkS")
		)
		(fp_line
			(start -0.7874 0.4064)
			(end -0.7874 -0.4064)
			(stroke
				(width 0.1524)
				(type default)
			)
			(layer "F.SilkS")
		)
		(fp_line
			(start -0.7874 -0.4064)
			(end 0.7874 -0.4064)
			(stroke
				(width 0.1524)
				(type default)
			)
			(layer "F.SilkS")
		)
		(fp_line
			(start 0.67945 0.3048)
			(end 0.120396 0.3048)
			(stroke
				(width 0.1)
				(type default)
			)
			(layer "F.Fab")
		)
		(fp_line
			(start 0.67945 -0.3048)
			(end 0.67945 0.3048)
			(stroke
				(width 0.1)
				(type default)
			)
			(layer "F.Fab")
		)
		(fp_line
			(start 0.12065 -0.2794)
			(end 0.12065 -0.3048)
			(stroke
				(width 0.1)
				(type default)
			)
			(layer "F.Fab")
		)
		(fp_line
			(start 0.12065 -0.3048)
			(end 0.67945 -0.3048)
			(stroke
				(width 0.1)
				(type default)
			)
			(layer "F.Fab")
		)
		(fp_line
			(start 0.120396 0.3048)
			(end 0.120396 0.2794)
			(stroke
				(width 0.1)
				(type default)
			)
			(layer "F.Fab")
		)
		(fp_line
			(start 0.120396 0.2794)
			(end -0.12065 0.2794)
			(stroke
				(width 0.1)
				(type default)
			)
			(layer "F.Fab")
		)
		(fp_line
			(start -0.12065 0.3048)
			(end -0.67945 0.3048)
			(stroke
				(width 0.1)
				(type default)
			)
			(layer "F.Fab")
		)
		(fp_line
			(start -0.12065 0.2794)
			(end -0.12065 0.3048)
			(stroke
				(width 0.1)
				(type default)
			)
			(layer "F.Fab")
		)
		(fp_line
			(start -0.12065 -0.2794)
			(end 0.12065 -0.2794)
			(stroke
				(width 0.1)
				(type default)
			)
			(layer "F.Fab")
		)
		(fp_line
			(start -0.12065 -0.305054)
			(end -0.12065 -0.2794)
			(stroke
				(width 0.1)
				(type default)
			)
			(layer "F.Fab")
		)
		(fp_line
			(start -0.67945 0.3048)
			(end -0.67945 -0.305054)
			(stroke
				(width 0.1)
				(type default)
			)
			(layer "F.Fab")
		)
		(fp_line
			(start -0.67945 -0.305054)
			(end -0.12065 -0.305054)
			(stroke
				(width 0.1)
				(type default)
			)
			(layer "F.Fab")
		)
		(pad "1" smd circle
			(at -0.40005 0 180)
			(size 0 0)
			(layers "F.Cu" "F.Mask" "F.Paste")
			(net "RST_PERST_CPU0_SWB_N")
		)
		(pad "2" smd circle
			(at 0.40005 0 180)
			(size 0 0)
			(layers "F.Cu" "F.Mask" "F.Paste")
			(net "GND")
		)
	)
	(footprint ""
		(layer "F.Cu")
		(at 451.327012 -30.397958 -90)
		(property "Reference" "PD101"
			(at 1.127506 -2.5654 90)
			(unlocked yes)
			(layer "F.SilkS")
			(effects
				(font
					(size 0.7874 0.5842)
					(thickness 0.1524)
				)
				(justify left)
			)
		)
		(property "Value" ""
			(at 0 0 270)
			(layer "F.Fab")
			(effects
				(font
					(size 1.27 1.27)
				)
			)
		)
		(duplicate_pad_numbers_are_jumpers no)
		(fp_line
			(start -2.250186 0.999998)
			(end 2.631186 0.999998)
			(stroke
				(width 0.1524)
				(type default)
			)
			(layer "F.SilkS")
		)
		(fp_line
			(start 2.631186 0.999998)
			(end 2.631186 -0.999998)
			(stroke
				(width 0.1524)
				(type default)
			)
			(layer "F.SilkS")
		)
		(fp_line
			(start -0.381 0.3302)
			(end -0.381 -0.4318)
			(stroke
				(width 0.1524)
				(type default)
			)
			(layer "F.SilkS")
		)
		(fp_line
			(start -0.381 -0.0508)
			(end -0.6604 -0.0508)
			(stroke
				(width 0.1524)
				(type default)
			)
			(layer "F.SilkS")
		)
		(fp_line
			(start 0.381 -0.0508)
			(end -0.381 0.3302)
			(stroke
				(width 0.1524)
				(type default)
			)
			(layer "F.SilkS")
		)
		(fp_line
			(start 0.381 -0.0508)
			(end 0.635 -0.0508)
			(stroke
				(width 0.1524)
				(type default)
			)
			(layer "F.SilkS")
		)
		(fp_line
			(start -0.381 -0.4318)
			(end 0.381 -0.0508)
			(stroke
				(width 0.1524)
				(type default)
			)
			(layer "F.SilkS")
		)
		(fp_line
			(start 0.381 -0.4318)
			(end 0.381 0.3302)
			(stroke
				(width 0.1524)
				(type default)
			)
			(layer "F.SilkS")
		)
		(fp_line
			(start -2.250186 -0.999998)
			(end -2.250186 0.999998)
			(stroke
				(width 0.1524)
				(type default)
			)
			(layer "F.SilkS")
		)
		(fp_line
			(start 2.631186 -0.999998)
			(end -2.250186 -0.999998)
			(stroke
				(width 0.1524)
				(type default)
			)
			(layer "F.SilkS")
		)
		(fp_rect
			(start 2.6162 1.016)
			(end 2.1844 -0.9652)
			(stroke
				(width 0)
				(type default)
			)
			(fill yes)
			(layer "F.SilkS")
		)
		(fp_line
			(start -1.450086 0.999998)
			(end 1.450086 0.999998)
			(stroke
				(width 0.1)
				(type default)
			)
			(layer "F.Fab")
		)
		(fp_line
			(start 1.450086 0.999998)
			(end 1.450086 -0.999998)
			(stroke
				(width 0.1)
				(type default)
			)
			(layer "F.Fab")
		)
		(fp_line
			(start -1.450086 -0.999998)
			(end -1.450086 0.999998)
			(stroke
				(width 0.1)
				(type default)
			)
			(layer "F.Fab")
		)
		(fp_line
			(start 1.450086 -0.999998)
			(end -1.450086 -0.999998)
			(stroke
				(width 0.1)
				(type default)
			)
			(layer "F.Fab")
		)
		(fp_text user "+"
			(at -3.4798 -0.22225 270)
			(unlocked yes)
			(layer "F.SilkS")
			(effects
				(font
					(size 1.905 1.4224)
					(thickness 0.1524)
				)
				(justify left)
			)
		)
		(fp_text user "-"
			(at 2.4384 -0.22225 270)
			(unlocked yes)
			(layer "F.SilkS")
			(effects
				(font
					(size 1.905 1.4224)
					(thickness 0.1524)
				)
				(justify left)
			)
		)
		(fp_text user "+"
			(at -3.4798 -0.22225 270)
			(unlocked yes)
			(layer "F.Fab")
			(effects
				(font
					(size 1.905 1.4224)
					(thickness 0.1524)
				)
				(justify left)
			)
		)
		(fp_text user "-"
			(at 2.4384 -0.22225 270)
			(unlocked yes)
			(layer "F.Fab")
			(effects
				(font
					(size 1.905 1.4224)
					(thickness 0.1524)
				)
				(justify left)
			)
		)
		(pad "A" smd rect
			(at -1.450086 0 270)
			(size 1.3208 1.4224)
			(layers "F.Cu" "F.Mask" "F.Paste")
			(net "GND")
		)
		(pad "C" smd rect
			(at 1.450086 0 270)
			(size 1.3208 1.4224)
			(layers "F.Cu" "F.Mask" "F.Paste")
			(net "P12V_AUX")
		)
	)
	(footprint ""
		(layer "F.Cu")
		(at 119.513096 -370.57203 -90)
		(property "Reference" "C1534"
			(at 0 0 270)
			(layer "F.SilkS")
			(hide yes)
			(effects
				(font
					(size 1.27 1.27)
				)
			)
		)
		(property "Value" ""
			(at 0 0 270)
			(layer "F.Fab")
			(effects
				(font
					(size 1.27 1.27)
				)
			)
		)
		(duplicate_pad_numbers_are_jumpers no)
		(fp_line
			(start -0.299974 0.150114)
			(end -0.299974 -0.150114)
			(stroke
				(width 0.1)
				(type default)
			)
			(layer "F.Fab")
		)
		(fp_line
			(start 0.299974 0.150114)
			(end -0.299974 0.150114)
			(stroke
				(width 0.1)
				(type default)
			)
			(layer "F.Fab")
		)
		(fp_line
			(start -0.299974 -0.150114)
			(end 0.299974 -0.150114)
			(stroke
				(width 0.1)
				(type default)
			)
			(layer "F.Fab")
		)
		(fp_line
			(start 0.299974 -0.150114)
			(end 0.299974 0.150114)
			(stroke
				(width 0.1)
				(type default)
			)
			(layer "F.Fab")
		)
		(pad "1" smd rect
			(at -0.2667 0 270)
			(size 0.3048 0.381)
			(layers "F.Cu" "F.Mask" "F.Paste")
			(net "P5E_CPU1_P3_TX_C_DN<6>")
		)
		(pad "2" smd rect
			(at 0.2667 0 270)
			(size 0.3048 0.381)
			(layers "F.Cu" "F.Mask" "F.Paste")
			(net "P5E_CPU1_P3_TX_DN<6>")
		)
	)
)
